# NUC Computer Cluster Power Breakout HW — KiCad project settings (.kicad_pro: net classes, design rules, text variables)
{
  "board": {
    "3dviewports": [],
    "design_settings": {
      "defaults": {
        "board_outline_line_width": 0.049999999999999996,
        "copper_line_width": 0.19999999999999998,
        "copper_text_italic": false,
        "copper_text_size_h": 1.5,
        "copper_text_size_v": 1.5,
        "copper_text_thickness": 0.3,
        "copper_text_upright": false,
        "courtyard_line_width": 0.049999999999999996,
        "dimension_precision": 4,
        "dimension_units": 3,
        "dimensions": {
          "arrow_length": 1270000,
          "extension_offset": 500000,
          "keep_text_aligned": true,
          "suppress_zeroes": false,
          "text_position": 0,
          "units_format": 1
        },
        "fab_line_width": 0.09999999999999999,
        "fab_text_italic": false,
        "fab_text_size_h": 1.0,
        "fab_text_size_v": 1.0,
        "fab_text_thickness": 0.15,
        "fab_text_upright": false,
        "other_line_width": 0.09999999999999999,
        "other_text_italic": false,
        "other_text_size_h": 1.0,
        "other_text_size_v": 1.0,
        "other_text_thickness": 0.15,
        "other_text_upright": false,
        "pads": {
          "drill": 1.19,
          "height": 2.19,
          "width": 1.74
        },
        "silk_line_width": 0.12,
        "silk_text_italic": false,
        "silk_text_size_h": 1.0,
        "silk_text_size_v": 1.0,
        "silk_text_thickness": 0.15,
        "silk_text_upright": false,
        "zones": {
          "45_degree_only": false,
          "min_clearance": 0.0
        }
      },
      "diff_pair_dimensions": [
        {
          "gap": 0.0,
          "via_gap": 0.0,
          "width": 0.0
        }
      ],
      "drc_exclusions": [],
      "meta": {
        "filename": "board_design_settings.json",
        "version": 2
      },
      "rule_severities": {
        "annular_width": "error",
        "clearance": "error",
        "connection_width": "warning",
        "copper_edge_clearance": "error",
        "copper_sliver": "warning",
        "courtyards_overlap": "error",
        "diff_pair_gap_out_of_range": "error",
        "diff_pair_uncoupled_length_too_long": "error",
        "drill_out_of_range": "error",
        "duplicate_footprints": "warning",
        "extra_footprint": "warning",
        "footprint": "error",
        "footprint_type_mismatch": "error",
        "hole_clearance": "error",
        "hole_near_hole": "error",
        "invalid_outline": "error",
        "isolated_copper": "warning",
        "item_on_disabled_layer": "error",
        "items_not_allowed": "error",
        "length_out_of_range": "error",
        "lib_footprint_issues": "warning",
        "lib_footprint_mismatch": "warning",
        "malformed_courtyard": "error",
        "microvia_drill_out_of_range": "error",
        "missing_courtyard": "ignore",
        "missing_footprint": "warning",
        "net_conflict": "warning",
        "npth_inside_courtyard": "ignore",
        "padstack": "error",
        "pth_inside_courtyard": "ignore",
        "shorting_items": "error",
        "silk_edge_clearance": "warning",
        "silk_over_copper": "warning",
        "silk_overlap": "warning",
        "skew_out_of_range": "error",
        "solder_mask_bridge": "error",
        "starved_thermal": "error",
        "text_height": "warning",
        "text_thickness": "warning",
        "through_hole_pad_without_hole": "error",
        "too_many_vias": "error",
        "track_dangling": "warning",
        "track_width": "error",
        "tracks_crossing": "error",
        "unconnected_items": "error",
        "unresolved_variable": "error",
        "via_dangling": "warning",
        "zones_intersect": "error"
      },
      "rule_severitieslegacy_courtyards_overlap": false,
      "rule_severitieslegacy_no_courtyard_defined": false,
      "rules": {
        "allow_blind_buried_vias": false,
        "allow_microvias": false,
        "max_error": 0.005,
        "min_clearance": 0.125,
        "min_connection": 0.0,
        "min_copper_edge_clearance": 0.3,
        "min_hole_clearance": 0.25,
        "min_hole_to_hole": 0.25,
        "min_microvia_diameter": 0.19999999999999998,
        "min_microvia_drill": 0.09999999999999999,
        "min_resolved_spokes": 1,
        "min_silk_clearance": 0.0,
        "min_text_height": 0.7,
        "min_text_thickness": 0.08,
        "min_through_hole_diameter": 0.19999999999999998,
        "min_track_width": 0.125,
        "min_via_annular_width": 0.175,
        "min_via_diameter": 0.6,
        "solder_mask_to_copper_clearance": 0.0,
        "use_height_for_length_calcs": true
      },
      "teardrop_options": [
        {
          "td_allow_use_two_tracks": true,
          "td_curve_segcount": 5,
          "td_on_pad_in_zone": false,
          "td_onpadsmd": true,
          "td_onroundshapesonly": false,
          "td_ontrackend": false,
          "td_onviapad": true
        }
      ],
      "teardrop_parameters": [
        {
          "td_curve_segcount": 0,
          "td_height_ratio": 1.0,
          "td_length_ratio": 0.5,
          "td_maxheight": 2.0,
          "td_maxlen": 1.0,
          "td_target_name": "td_round_shape",
          "td_width_to_size_filter_ratio": 0.9
        },
        {
          "td_curve_segcount": 0,
          "td_height_ratio": 1.0,
          "td_length_ratio": 0.5,
          "td_maxheight": 2.0,
          "td_maxlen": 1.0,
          "td_target_name": "td_rect_shape",
          "td_width_to_size_filter_ratio": 0.9
        },
        {
          "td_curve_segcount": 0,
          "td_height_ratio": 1.0,
          "td_length_ratio": 0.5,
          "td_maxheight": 2.0,
          "td_maxlen": 1.0,
          "td_target_name": "td_track_end",
          "td_width_to_size_filter_ratio": 0.9
        }
      ],
      "track_widths": [
        0.0,
        0.2,
        0.25,
        0.325,
        0.4,
        0.5,
        0.6,
        0.7,
        0.8,
        1.0
      ],
      "via_dimensions": [
        {
          "diameter": 0.0,
          "drill": 0.0
        },
        {
          "diameter": 0.6,
          "drill": 0.25
        },
        {
          "diameter": 0.8,
          "drill": 0.4
        }
      ],
      "zones_allow_external_fillets": false,
      "zones_use_no_outline": true
    },
    "layer_presets": [],
    "viewports": []
  },
  "boards": [],
  "cvpcb": {
    "equivalence_files": []
  },
  "erc": {
    "erc_exclusions": [],
    "meta": {
      "version": 0
    },
    "pin_map": [
      [
        0,
        0,
        0,
        0,
        0,
        0,
        1,
        0,
        0,
        0,
        0,
        2
      ],
      [
        0,
        2,
        0,
        1,
        0,
        0,
        1,
        0,
        2,
        2,
        2,
        2
      ],
      [
        0,
        0,
        0,
        0,
        0,
        0,
        1,
        0,
        1,
        0,
        1,
        2
      ],
      [
        0,
        1,
        0,
        0,
        0,
        0,
        1,
        1,
        2,
        1,
        1,
        2
      ],
      [
        0,
        0,
        0,
        0,
        0,
        0,
        1,
        0,
        0,
        0,
        0,
        2
      ],
      [
        0,
        0,
        0,
        0,
        0,
        0,
        0,
        0,
        0,
        0,
        0,
        2
      ],
      [
        1,
        1,
        1,
        1,
        1,
        0,
        1,
        1,
        1,
        1,
        1,
        2
      ],
      [
        0,
        0,
        0,
        1,
        0,
        0,
        1,
        0,
        0,
        0,
        0,
        2
      ],
      [
        0,
        2,
        1,
        2,
        0,
        0,
        1,
        0,
        2,
        2,
        2,
        2
      ],
      [
        0,
        2,
        0,
        1,
        0,
        0,
        1,
        0,
        2,
        0,
        0,
        2
      ],
      [
        0,
        2,
        1,
        1,
        0,
        0,
        1,
        0,
        2,
        0,
        0,
        2
      ],
      [
        2,
        2,
        2,
        2,
        2,
        2,
        2,
        2,
        2,
        2,
        2,
        2
      ]
    ],
    "rule_severities": {
      "bus_definition_conflict": "error",
      "bus_entry_needed": "error",
      "bus_to_bus_conflict": "error",
      "bus_to_net_conflict": "error",
      "conflicting_netclasses": "error",
      "different_unit_footprint": "error",
      "different_unit_net": "error",
      "duplicate_reference": "error",
      "duplicate_sheet_names": "error",
      "endpoint_off_grid": "warning",
      "extra_units": "error",
      "global_label_dangling": "warning",
      "hier_label_mismatch": "error",
      "label_dangling": "error",
      "lib_symbol_issues": "warning",
      "missing_bidi_pin": "warning",
      "missing_input_pin": "warning",
      "missing_power_pin": "error",
      "missing_unit": "warning",
      "multiple_net_names": "warning",
      "net_not_bus_member": "warning",
      "no_connect_connected": "error",
      "no_connect_dangling": "warning",
      "pin_not_connected": "error",
      "pin_not_driven": "error",
      "pin_to_pin": "error",
      "power_pin_not_driven": "error",
      "similar_labels": "warning",
      "simulation_model_issue": "ignore",
      "unannotated": "error",
      "unit_value_mismatch": "error",
      "unresolved_variable": "error",
      "wire_dangling": "error"
    }
  },
  "libraries": {
    "pinned_footprint_libs": [],
    "pinned_symbol_libs": []
  },
  "meta": {
    "filename": "d1600e-psu-breakout-board.kicad_pro",
    "version": 1
  },
  "net_settings": {
    "classes": [
      {
        "bus_width": 12,
        "clearance": 0.127,
        "diff_pair_gap": 0.25,
        "diff_pair_via_gap": 0.25,
        "diff_pair_width": 0.2,
        "line_style": 0,
        "microvia_diameter": 0.3,
        "microvia_drill": 0.1,
        "name": "Default",
        "pcb_color": "rgba(0, 0, 0, 0.000)",
        "schematic_color": "rgba(0, 0, 0, 0.000)",
        "track_width": 0.25,
        "via_diameter": 0.8,
        "via_drill": 0.4,
        "wire_width": 6
      },
      {
        "bus_width": 12,
        "clearance": 0.127,
        "diff_pair_gap": 0.25,
        "diff_pair_via_gap": 0.25,
        "diff_pair_width": 0.2,
        "line_style": 0,
        "microvia_diameter": 0.3,
        "microvia_drill": 0.1,
        "name": "Power",
        "pcb_color": "rgba(0, 0, 0, 0.000)",
        "schematic_color": "rgba(0, 0, 0, 0.000)",
        "track_width": 0.25,
        "via_diameter": 0.8,
        "via_drill": 0.4,
        "wire_width": 6
      },
      {
        "bus_width": 12,
        "clearance": 0.127,
        "diff_pair_gap": 0.127,
        "diff_pair_via_gap": 0.25,
        "diff_pair_width": 0.325,
        "line_style": 0,
        "microvia_diameter": 0.3,
        "microvia_drill": 0.1,
        "name": "USB_Diff",
        "pcb_color": "rgba(0, 0, 0, 0.000)",
        "schematic_color": "rgba(0, 0, 0, 0.000)",
        "track_width": 0.25,
        "via_diameter": 0.8,
        "via_drill": 0.4,
        "wire_width": 6
      }
    ],
    "meta": {
      "version": 3
    },
    "net_colors": null,
    "netclass_assignments": null,
    "netclass_patterns": [
      {
        "netclass": "Power",
        "pattern": "C_MEAS_1"
      },
      {
        "netclass": "Power",
        "pattern": "C_MEAS_2"
      },
      {
        "netclass": "Power",
        "pattern": "C_MEAS_3"
      },
      {
        "netclass": "Power",
        "pattern": "C_MEAS_4"
      },
      {
        "netclass": "Power",
        "pattern": "C_MEAS_5"
      },
      {
        "netclass": "Power",
        "pattern": "GND"
      },
      {
        "netclass": "Power",
        "pattern": "GNDD"
      },
      {
        "netclass": "Power",
        "pattern": "LOAD_1"
      },
      {
        "netclass": "Power",
        "pattern": "LOAD_2"
      },
      {
        "netclass": "Power",
        "pattern": "LOAD_3"
      },
      {
        "netclass": "Power",
        "pattern": "LOAD_4"
      },
      {
        "netclass": "Power",
        "pattern": "LOAD_5"
      },
      {
        "netclass": "Power",
        "pattern": "VBUS"
      },
      {
        "netclass": "Power",
        "pattern": "VCC12V0"
      },
      {
        "netclass": "Power",
        "pattern": "VCC3V3"
      },
      {
        "netclass": "Power",
        "pattern": "VCC3V3_USB"
      },
      {
        "netclass": "Power",
        "pattern": "VCC5V0"
      },
      {
        "netclass": "Power",
        "pattern": "VCC5V0_USB"
      },
      {
        "netclass": "USB_Diff",
        "pattern": "/FTDI/USB_D+"
      },
      {
        "netclass": "USB_Diff",
        "pattern": "/FTDI/USB_D-"
      }
    ]
  },
  "pcbnew": {
    "last_paths": {
      "gencad": "",
      "idf": "",
      "netlist": "",
      "specctra_dsn": "",
      "step": "",
      "vrml": ""
    },
    "page_layout_descr_file": ""
  },
  "schematic": {
    "annotate_start_num": 0,
    "drawing": {
      "dashed_lines_dash_length_ratio": 12.0,
      "dashed_lines_gap_length_ratio": 3.0,
      "default_line_thickness": 6.0,
      "default_text_size": 50.0,
      "field_names": [],
      "intersheets_ref_own_page": false,
      "intersheets_ref_prefix": "",
      "intersheets_ref_short": false,
      "intersheets_ref_show": false,
      "intersheets_ref_suffix": "",
      "junction_size_choice": 3,
      "label_size_ratio": 0.25,
      "pin_symbol_size": 0.0,
      "text_offset_ratio": 0.08
    },
    "legacy_lib_dir": "",
    "legacy_lib_list": [],
    "meta": {
      "version": 1
    },
    "net_format_name": "Pcbnew",
    "ngspice": {
      "fix_include_paths": true,
      "fix_passive_vals": false,
      "meta": {
        "version": 0
      },
      "model_mode": 0,
      "workbook_filename": ""
    },
    "page_layout_descr_file": "",
    "plot_directory": "",
    "spice_adjust_passive_values": false,
    "spice_current_sheet_as_root": false,
    "spice_external_command": "spice \"%I\"",
    "spice_model_current_sheet_as_root": true,
    "spice_save_all_currents": false,
    "spice_save_all_voltages": false,
    "subpart_first_id": 65,
    "subpart_id_separator": 0
  },
  "sheets": [
    [
      "",
      ""
    ],
    [
      "",
      "FTDI"
    ],
    [
      "",
      "Power Cycling & Current Measurement"
    ],
    [
      "",
      "daughterboard-supply"
    ],
    [
      "",
      "Power switch 1"
    ],
    [
      "",
      "Power switch 2"
    ],
    [
      "",
      "Power switch 3"
    ],
    [
      "",
      "Power switch 4"
    ],
    [
      "",
      "Power switch 5"
    ]
  ],
  "text_variables": {}
}
